(kicad_pcb
	(version 20260206)
	(generator "pcbnew")
	(generator_version "10.0")
	(general
		(thickness 1.6)
		(legacy_teardrops no)
	)
	(paper "A4")
	(title_block
		(title "Bryce Canyon_IOM_IOC_16318-2_OCP.brd")
		(comment 1 "Bryce Canyon / footprint 592 of 1605 (U1), pads 1-119 of 896")
	)
	(layers
		(0 "F.Cu" signal "TOP")
		(4 "In1.Cu" signal "L2GND")
		(6 "In2.Cu" signal "L3")
		(8 "In3.Cu" signal "L4VCC")
		(10 "In4.Cu" signal "L5VCC")
		(12 "In5.Cu" signal "L6")
		(14 "In6.Cu" signal "L7GND")
		(2 "B.Cu" signal "BOTTOM")
		(9 "F.Adhes" user "F.Adhesive")
		(11 "B.Adhes" user "B.Adhesive")
		(13 "F.Paste" user "Package Geometry/Pastemask Top")
		(15 "B.Paste" user "Package Geometry/Pastemask Bottom")
		(5 "F.SilkS" user "Ref Des/Silkscreen Top")
		(7 "B.SilkS" user "Ref Des/Silkscreen Bottom")
		(1 "F.Mask" user "Board Geometry/Soldermask Top")
		(3 "B.Mask" user "Board Geometry/Soldermask Bottom")
		(17 "Dwgs.User" user "User.Drawings")
		(19 "Cmts.User" user "User.Comments")
		(21 "Eco1.User" user "User.Eco1")
		(23 "Eco2.User" user "User.Eco2")
		(25 "Edge.Cuts" user "Board Geometry/Outline")
		(27 "Margin" user)
		(31 "F.CrtYd" user "Package Geometry/Place Bound Top")
		(29 "B.CrtYd" user "Package Geometry/Place Bound Bottom")
		(35 "F.Fab" user "Ref Des/Assembly Top")
		(33 "B.Fab" user "Ref Des/Assembly Bottom")
	)
	(footprint ""
		(layer "F.Cu")
		(at 192.79997 -65.099946 180)
		(property "Reference" "U1"
			(at 0 0 180)
			(layer "F.SilkS")
			(hide yes)
			(effects
				(font
					(size 1.27 1.27)
				)
			)
		)
		(property "Value" "SAS3008C0-1-DB-500020657-1-GP"
			(at -20.374102 -5.0292 180)
			(unlocked yes)
			(layer "F.Fab")
			(hide yes)
			(effects
				(font
					(size 1.016 1.016)
					(thickness 0.1524)
				)
			)
		)
		(property "Device Type" "BGA896D25H78"
			(at -20.374102 -6.5532 180)
			(unlocked yes)
			(layer "F.Fab")
			(hide yes)
			(effects
				(font
					(size 1.016 1.016)
					(thickness 0.1524)
				)
			)
		)
		(duplicate_pad_numbers_are_jumpers no)
		(pad "A2" smd circle
			(at -10.80008 -11.599926 180)
			(size 0.4064 0.4064)
			(layers "F.Cu" "F.Mask" "F.Paste")
			(net "Net_1211")
		)
		(pad "A3" smd circle
			(at -9.99998 -11.599926 180)
			(size 0.4064 0.4064)
			(layers "F.Cu" "F.Mask" "F.Paste")
			(net "Net_1212")
		)
		(pad "A4" smd circle
			(at -9.19988 -11.599926 180)
			(size 0.3556 0.3556)
			(layers "F.Cu" "F.Mask" "F.Paste")
			(net "GND")
		)
		(pad "A5" smd circle
			(at -8.400034 -11.599926 180)
			(size 0.3556 0.3556)
			(layers "F.Cu" "F.Mask" "F.Paste")
			(net "Net_1213")
		)
		(pad "A6" smd circle
			(at -7.599934 -11.599926 180)
			(size 0.3556 0.3556)
			(layers "F.Cu" "F.Mask" "F.Paste")
			(net "ICE1_TMS")
		)
		(pad "A7" smd circle
			(at -6.800088 -11.599926 180)
			(size 0.3556 0.3556)
			(layers "F.Cu" "F.Mask" "F.Paste")
			(net "Net_1214")
		)
		(pad "A8" smd circle
			(at -5.999988 -11.599926 180)
			(size 0.3556 0.3556)
			(layers "F.Cu" "F.Mask" "F.Paste")
			(net "ICE0_TRST#")
		)
		(pad "A9" smd circle
			(at -5.199888 -11.599926 180)
			(size 0.3556 0.3556)
			(layers "F.Cu" "F.Mask" "F.Paste")
			(net "ICE0_TCK")
		)
		(pad "A10" smd circle
			(at -4.400042 -11.599926 180)
			(size 0.3556 0.3556)
			(layers "F.Cu" "F.Mask" "F.Paste")
			(net "ICE1_TDO")
		)
		(pad "A11" smd circle
			(at -3.599942 -11.599926 180)
			(size 0.3556 0.3556)
			(layers "F.Cu" "F.Mask" "F.Paste")
			(net "GND")
		)
		(pad "A12" smd circle
			(at -2.800096 -11.599926 180)
			(size 0.3556 0.3556)
			(layers "F.Cu" "F.Mask" "F.Paste")
			(net "Net_1204")
		)
		(pad "A13" smd circle
			(at -1.999996 -11.599926 180)
			(size 0.3556 0.3556)
			(layers "F.Cu" "F.Mask" "F.Paste")
			(net "PWRGD_P0V975")
		)
		(pad "A14" smd circle
			(at -1.199896 -11.599926 180)
			(size 0.3556 0.3556)
			(layers "F.Cu" "F.Mask" "F.Paste")
			(net "HM40ADC_VDDA")
		)
		(pad "A15" smd circle
			(at -0.40005 -11.599926 180)
			(size 0.3556 0.3556)
			(layers "F.Cu" "F.Mask" "F.Paste")
			(net "GND")
		)
		(pad "A16" smd circle
			(at 0.40005 -11.599926 180)
			(size 0.3556 0.3556)
			(layers "F.Cu" "F.Mask" "F.Paste")
			(net "IOC_TRST_N")
		)
		(pad "A17" smd circle
			(at 1.199896 -11.599926 180)
			(size 0.3556 0.3556)
			(layers "F.Cu" "F.Mask" "F.Paste")
			(net "JTAG_IOC_TDI")
		)
		(pad "A18" smd circle
			(at 1.999996 -11.599926 180)
			(size 0.3556 0.3556)
			(layers "F.Cu" "F.Mask" "F.Paste")
			(net "LSI_IDDT")
		)
		(pad "A19" smd circle
			(at 2.800096 -11.599926 180)
			(size 0.3556 0.3556)
			(layers "F.Cu" "F.Mask" "F.Paste")
			(net "Net_1205")
		)
		(pad "A20" smd circle
			(at 3.599942 -11.599926 180)
			(size 0.3556 0.3556)
			(layers "F.Cu" "F.Mask" "F.Paste")
			(net "Net_1206")
		)
		(pad "A21" smd circle
			(at 4.400042 -11.599926 180)
			(size 0.3556 0.3556)
			(layers "F.Cu" "F.Mask" "F.Paste")
			(net "XM_NOR_CS_N")
		)
		(pad "A22" smd circle
			(at 5.199888 -11.599926 180)
			(size 0.3556 0.3556)
			(layers "F.Cu" "F.Mask" "F.Paste")
			(net "XM_RB")
		)
		(pad "A23" smd circle
			(at 5.999988 -11.599926 180)
			(size 0.3556 0.3556)
			(layers "F.Cu" "F.Mask" "F.Paste")
			(net "Net_1200")
		)
		(pad "A24" smd circle
			(at 6.800088 -11.599926 180)
			(size 0.3556 0.3556)
			(layers "F.Cu" "F.Mask" "F.Paste")
			(net "XM_WE_N")
		)
		(pad "A25" smd circle
			(at 7.599934 -11.599926 180)
			(size 0.3556 0.3556)
			(layers "F.Cu" "F.Mask" "F.Paste")
			(net "XM_WP")
		)
		(pad "A26" smd circle
			(at 8.400034 -11.599926 180)
			(size 0.3556 0.3556)
			(layers "F.Cu" "F.Mask" "F.Paste")
			(net "XM_ADDR_3")
		)
		(pad "A27" smd circle
			(at 9.19988 -11.599926 180)
			(size 0.3556 0.3556)
			(layers "F.Cu" "F.Mask" "F.Paste")
			(net "Net_1201")
		)
		(pad "A28" smd circle
			(at 9.99998 -11.599926 180)
			(size 0.4064 0.4064)
			(layers "F.Cu" "F.Mask" "F.Paste")
			(net "XM_ADDR_4")
		)
		(pad "A29" smd circle
			(at 10.80008 -11.599926 180)
			(size 0.4064 0.4064)
			(layers "F.Cu" "F.Mask" "F.Paste")
			(net "XM_DATA_11")
		)
		(pad "AA1" smd circle
			(at -11.599926 4.400042 180)
			(size 0.3556 0.3556)
			(layers "F.Cu" "F.Mask" "F.Paste")
			(net "PHY_IOC_TO_CON_B_1_DP_C")
		)
		(pad "AA2" smd circle
			(at -10.80008 4.400042 180)
			(size 0.3556 0.3556)
			(layers "F.Cu" "F.Mask" "F.Paste")
			(net "PHY_IOC_TO_CON_B_1_DN_C")
		)
		(pad "AA3" smd circle
			(at -9.99998 4.400042 180)
			(size 0.3556 0.3556)
			(layers "F.Cu" "F.Mask" "F.Paste")
			(net "GND")
		)
		(pad "AA4" smd circle
			(at -9.19988 4.400042 180)
			(size 0.3556 0.3556)
			(layers "F.Cu" "F.Mask" "F.Paste")
			(net "PHY_CON_B_TO_IOC_1_DP")
		)
		(pad "AA5" smd circle
			(at -8.400034 4.400042 180)
			(size 0.3556 0.3556)
			(layers "F.Cu" "F.Mask" "F.Paste")
			(net "PHY_CON_B_TO_IOC_1_DN")
		)
		(pad "AA6" smd circle
			(at -7.599934 4.400042 180)
			(size 0.3556 0.3556)
			(layers "F.Cu" "F.Mask" "F.Paste")
			(net "GND")
		)
		(pad "AA7" smd circle
			(at -6.800088 4.400042 180)
			(size 0.3556 0.3556)
			(layers "F.Cu" "F.Mask" "F.Paste")
			(net "GND")
		)
		(pad "AA8" smd circle
			(at -5.999988 4.400042 180)
			(size 0.3556 0.3556)
			(layers "F.Cu" "F.Mask" "F.Paste")
			(net "GND")
		)
		(pad "AA9" smd circle
			(at -5.199888 4.400042 180)
			(size 0.3556 0.3556)
			(layers "F.Cu" "F.Mask" "F.Paste")
			(net "GND")
		)
		(pad "AA10" smd circle
			(at -4.400042 4.400042 180)
			(size 0.3556 0.3556)
			(layers "F.Cu" "F.Mask" "F.Paste")
			(net "GND")
		)
		(pad "AA11" smd circle
			(at -3.599942 4.400042 180)
			(size 0.3556 0.3556)
			(layers "F.Cu" "F.Mask" "F.Paste")
			(net "GND")
		)
		(pad "AA12" smd circle
			(at -2.800096 4.400042 180)
			(size 0.3556 0.3556)
			(layers "F.Cu" "F.Mask" "F.Paste")
			(net "GND")
		)
		(pad "AA13" smd circle
			(at -1.999996 4.400042 180)
			(size 0.3556 0.3556)
			(layers "F.Cu" "F.Mask" "F.Paste")
			(net "GND")
		)
		(pad "AA14" smd circle
			(at -1.199896 4.400042 180)
			(size 0.3556 0.3556)
			(layers "F.Cu" "F.Mask" "F.Paste")
			(net "GND")
		)
		(pad "AA15" smd circle
			(at -0.40005 4.400042 180)
			(size 0.3556 0.3556)
			(layers "F.Cu" "F.Mask" "F.Paste")
			(net "GND")
		)
		(pad "AA16" smd circle
			(at 0.40005 4.400042 180)
			(size 0.3556 0.3556)
			(layers "F.Cu" "F.Mask" "F.Paste")
			(net "GND")
		)
		(pad "AA17" smd circle
			(at 1.199896 4.400042 180)
			(size 0.3556 0.3556)
			(layers "F.Cu" "F.Mask" "F.Paste")
			(net "GND")
		)
		(pad "AA18" smd circle
			(at 1.999996 4.400042 180)
			(size 0.3556 0.3556)
			(layers "F.Cu" "F.Mask" "F.Paste")
			(net "GND")
		)
		(pad "AA19" smd circle
			(at 2.800096 4.400042 180)
			(size 0.3556 0.3556)
			(layers "F.Cu" "F.Mask" "F.Paste")
			(net "GND")
		)
		(pad "AA20" smd circle
			(at 3.599942 4.400042 180)
			(size 0.3556 0.3556)
			(layers "F.Cu" "F.Mask" "F.Paste")
			(net "GND")
		)
		(pad "AA21" smd circle
			(at 4.400042 4.400042 180)
			(size 0.3556 0.3556)
			(layers "F.Cu" "F.Mask" "F.Paste")
			(net "GND")
		)
		(pad "AA22" smd circle
			(at 5.199888 4.400042 180)
			(size 0.3556 0.3556)
			(layers "F.Cu" "F.Mask" "F.Paste")
			(net "GND")
		)
		(pad "AA23" smd circle
			(at 5.999988 4.400042 180)
			(size 0.3556 0.3556)
			(layers "F.Cu" "F.Mask" "F.Paste")
			(net "PLL_VDD")
		)
		(pad "AA24" smd circle
			(at 6.800088 4.400042 180)
			(size 0.3556 0.3556)
			(layers "F.Cu" "F.Mask" "F.Paste")
			(net "GND")
		)
		(pad "AA25" smd circle
			(at 7.599934 4.400042 180)
			(size 0.3556 0.3556)
			(layers "F.Cu" "F.Mask" "F.Paste")
			(net "GND")
		)
		(pad "AA26" smd circle
			(at 8.400034 4.400042 180)
			(size 0.3556 0.3556)
			(layers "F.Cu" "F.Mask" "F.Paste")
			(net "GND")
		)
		(pad "AA27" smd circle
			(at 9.19988 4.400042 180)
			(size 0.3556 0.3556)
			(layers "F.Cu" "F.Mask" "F.Paste")
			(net "P1V8")
		)
		(pad "AA28" smd circle
			(at 9.99998 4.400042 180)
			(size 0.3556 0.3556)
			(layers "F.Cu" "F.Mask" "F.Paste")
			(net "IOC_EXT1_LED_B")
		)
		(pad "AA29" smd circle
			(at 10.80008 4.400042 180)
			(size 0.3556 0.3556)
			(layers "F.Cu" "F.Mask" "F.Paste")
			(net "IOC_GPIO_33")
		)
		(pad "AA30" smd circle
			(at 11.599926 4.400042 180)
			(size 0.3556 0.3556)
			(layers "F.Cu" "F.Mask" "F.Paste")
			(net "IOC_EXT1_LED_Y")
		)
		(pad "AB1" smd circle
			(at -11.599926 5.199888 180)
			(size 0.3556 0.3556)
			(layers "F.Cu" "F.Mask" "F.Paste")
			(net "PHY_IOC_TO_CON_B_0_DP_C")
		)
		(pad "AB2" smd circle
			(at -10.80008 5.199888 180)
			(size 0.3556 0.3556)
			(layers "F.Cu" "F.Mask" "F.Paste")
			(net "PHY_IOC_TO_CON_B_0_DN_C")
		)
		(pad "AB3" smd circle
			(at -9.99998 5.199888 180)
			(size 0.3556 0.3556)
			(layers "F.Cu" "F.Mask" "F.Paste")
			(net "GND")
		)
		(pad "AB4" smd circle
			(at -9.19988 5.199888 180)
			(size 0.3556 0.3556)
			(layers "F.Cu" "F.Mask" "F.Paste")
			(net "PHY_CON_B_TO_IOC_0_DP")
		)
		(pad "AB5" smd circle
			(at -8.400034 5.199888 180)
			(size 0.3556 0.3556)
			(layers "F.Cu" "F.Mask" "F.Paste")
			(net "PHY_CON_B_TO_IOC_0_DN")
		)
		(pad "AB6" smd circle
			(at -7.599934 5.199888 180)
			(size 0.3556 0.3556)
			(layers "F.Cu" "F.Mask" "F.Paste")
			(net "GND")
		)
		(pad "AB7" smd circle
			(at -6.800088 5.199888 180)
			(size 0.3556 0.3556)
			(layers "F.Cu" "F.Mask" "F.Paste")
			(net "SAS0_AVDD")
		)
		(pad "AB8" smd circle
			(at -5.999988 5.199888 180)
			(size 0.3556 0.3556)
			(layers "F.Cu" "F.Mask" "F.Paste")
			(net "GND")
		)
		(pad "AB9" smd circle
			(at -5.199888 5.199888 180)
			(size 0.3556 0.3556)
			(layers "F.Cu" "F.Mask" "F.Paste")
			(net "GND")
		)
		(pad "AB10" smd circle
			(at -4.400042 5.199888 180)
			(size 0.3556 0.3556)
			(layers "F.Cu" "F.Mask" "F.Paste")
			(net "GND")
		)
		(pad "AB11" smd circle
			(at -3.599942 5.199888 180)
			(size 0.3556 0.3556)
			(layers "F.Cu" "F.Mask" "F.Paste")
			(net "GND")
		)
		(pad "AB12" smd circle
			(at -2.800096 5.199888 180)
			(size 0.3556 0.3556)
			(layers "F.Cu" "F.Mask" "F.Paste")
			(net "GND")
		)
		(pad "AB13" smd circle
			(at -1.999996 5.199888 180)
			(size 0.3556 0.3556)
			(layers "F.Cu" "F.Mask" "F.Paste")
			(net "GND")
		)
		(pad "AB14" smd circle
			(at -1.199896 5.199888 180)
			(size 0.3556 0.3556)
			(layers "F.Cu" "F.Mask" "F.Paste")
			(net "GND")
		)
		(pad "AB15" smd circle
			(at -0.40005 5.199888 180)
			(size 0.3556 0.3556)
			(layers "F.Cu" "F.Mask" "F.Paste")
			(net "GND")
		)
		(pad "AB16" smd circle
			(at 0.40005 5.199888 180)
			(size 0.3556 0.3556)
			(layers "F.Cu" "F.Mask" "F.Paste")
			(net "GND")
		)
		(pad "AB17" smd circle
			(at 1.199896 5.199888 180)
			(size 0.3556 0.3556)
			(layers "F.Cu" "F.Mask" "F.Paste")
			(net "GND")
		)
		(pad "AB18" smd circle
			(at 1.999996 5.199888 180)
			(size 0.3556 0.3556)
			(layers "F.Cu" "F.Mask" "F.Paste")
			(net "GND")
		)
		(pad "AB19" smd circle
			(at 2.800096 5.199888 180)
			(size 0.3556 0.3556)
			(layers "F.Cu" "F.Mask" "F.Paste")
			(net "GND")
		)
		(pad "AB20" smd circle
			(at 3.599942 5.199888 180)
			(size 0.3556 0.3556)
			(layers "F.Cu" "F.Mask" "F.Paste")
			(net "GND")
		)
		(pad "AB21" smd circle
			(at 4.400042 5.199888 180)
			(size 0.3556 0.3556)
			(layers "F.Cu" "F.Mask" "F.Paste")
			(net "GND")
		)
		(pad "AB22" smd circle
			(at 5.199888 5.199888 180)
			(size 0.3556 0.3556)
			(layers "F.Cu" "F.Mask" "F.Paste")
			(net "GND")
		)
		(pad "AB23" smd circle
			(at 5.999988 5.199888 180)
			(size 0.3556 0.3556)
			(layers "F.Cu" "F.Mask" "F.Paste")
			(net "GND")
		)
		(pad "AB24" smd circle
			(at 6.800088 5.199888 180)
			(size 0.3556 0.3556)
			(layers "F.Cu" "F.Mask" "F.Paste")
			(net "GND")
		)
		(pad "AB25" smd circle
			(at 7.599934 5.199888 180)
			(size 0.3556 0.3556)
			(layers "F.Cu" "F.Mask" "F.Paste")
			(net "GND")
		)
		(pad "AB26" smd circle
			(at 8.400034 5.199888 180)
			(size 0.3556 0.3556)
			(layers "F.Cu" "F.Mask" "F.Paste")
			(net "P1V8")
		)
		(pad "AB27" smd circle
			(at 9.19988 5.199888 180)
			(size 0.3556 0.3556)
			(layers "F.Cu" "F.Mask" "F.Paste")
			(net "GND")
		)
		(pad "AB28" smd circle
			(at 9.99998 5.199888 180)
			(size 0.3556 0.3556)
			(layers "F.Cu" "F.Mask" "F.Paste")
			(net "IOC_GPIO_34")
		)
		(pad "AB29" smd circle
			(at 10.80008 5.199888 180)
			(size 0.3556 0.3556)
			(layers "F.Cu" "F.Mask" "F.Paste")
			(net "IOC_GPIO_23")
		)
		(pad "AB30" smd circle
			(at 11.599926 5.199888 180)
			(size 0.3556 0.3556)
			(layers "F.Cu" "F.Mask" "F.Paste")
			(net "IOC_GPIO_35")
		)
		(pad "AC1" smd circle
			(at -11.599926 5.999988 180)
			(size 0.3556 0.3556)
			(layers "F.Cu" "F.Mask" "F.Paste")
			(net "SAS0_VDDH")
		)
		(pad "AC2" smd circle
			(at -10.80008 5.999988 180)
			(size 0.3556 0.3556)
			(layers "F.Cu" "F.Mask" "F.Paste")
			(net "GND")
		)
		(pad "AC3" smd circle
			(at -9.99998 5.999988 180)
			(size 0.3556 0.3556)
			(layers "F.Cu" "F.Mask" "F.Paste")
			(net "GND")
		)
		(pad "AC4" smd circle
			(at -9.19988 5.999988 180)
			(size 0.3556 0.3556)
			(layers "F.Cu" "F.Mask" "F.Paste")
			(net "SAS0_AVDD")
		)
		(pad "AC5" smd circle
			(at -8.400034 5.999988 180)
			(size 0.3556 0.3556)
			(layers "F.Cu" "F.Mask" "F.Paste")
			(net "GND")
		)
		(pad "AC6" smd circle
			(at -7.599934 5.999988 180)
			(size 0.3556 0.3556)
			(layers "F.Cu" "F.Mask" "F.Paste")
			(net "SAS0_VDDH")
		)
		(pad "AC7" smd circle
			(at -6.800088 5.999988 180)
			(size 0.3556 0.3556)
			(layers "F.Cu" "F.Mask" "F.Paste")
			(net "GND")
		)
		(pad "AC8" smd circle
			(at -5.999988 5.999988 180)
			(size 0.3556 0.3556)
			(layers "F.Cu" "F.Mask" "F.Paste")
			(net "GND")
		)
		(pad "AC9" smd circle
			(at -5.199888 5.999988 180)
			(size 0.3556 0.3556)
			(layers "F.Cu" "F.Mask" "F.Paste")
			(net "GND")
		)
		(pad "AC10" smd circle
			(at -4.400042 5.999988 180)
			(size 0.3556 0.3556)
			(layers "F.Cu" "F.Mask" "F.Paste")
			(net "GND")
		)
		(pad "AC11" smd circle
			(at -3.599942 5.999988 180)
			(size 0.3556 0.3556)
			(layers "F.Cu" "F.Mask" "F.Paste")
			(net "PCE_AVDD")
		)
		(pad "AC12" smd circle
			(at -2.800096 5.999988 180)
			(size 0.3556 0.3556)
			(layers "F.Cu" "F.Mask" "F.Paste")
			(net "GND")
		)
		(pad "AC13" smd circle
			(at -1.999996 5.999988 180)
			(size 0.3556 0.3556)
			(layers "F.Cu" "F.Mask" "F.Paste")
			(net "GND")
		)
		(pad "AC14" smd circle
			(at -1.199896 5.999988 180)
			(size 0.3556 0.3556)
			(layers "F.Cu" "F.Mask" "F.Paste")
			(net "GND")
		)
		(pad "AC15" smd circle
			(at -0.40005 5.999988 180)
			(size 0.3556 0.3556)
			(layers "F.Cu" "F.Mask" "F.Paste")
			(net "GND")
		)
		(pad "AC16" smd circle
			(at 0.40005 5.999988 180)
			(size 0.3556 0.3556)
			(layers "F.Cu" "F.Mask" "F.Paste")
			(net "GND")
		)
		(pad "AC17" smd circle
			(at 1.199896 5.999988 180)
			(size 0.3556 0.3556)
			(layers "F.Cu" "F.Mask" "F.Paste")
			(net "GND")
		)
		(pad "AC18" smd circle
			(at 1.999996 5.999988 180)
			(size 0.3556 0.3556)
			(layers "F.Cu" "F.Mask" "F.Paste")
			(net "GND")
		)
		(pad "AC19" smd circle
			(at 2.800096 5.999988 180)
			(size 0.3556 0.3556)
			(layers "F.Cu" "F.Mask" "F.Paste")
			(net "GND")
		)
		(pad "AC20" smd circle
			(at 3.599942 5.999988 180)
			(size 0.3556 0.3556)
			(layers "F.Cu" "F.Mask" "F.Paste")
			(net "GND")
		)
		(pad "AC21" smd circle
			(at 4.400042 5.999988 180)
			(size 0.3556 0.3556)
			(layers "F.Cu" "F.Mask" "F.Paste")
			(net "GND")
		)
		(pad "AC22" smd circle
			(at 5.199888 5.999988 180)
			(size 0.3556 0.3556)
			(layers "F.Cu" "F.Mask" "F.Paste")
			(net "GND")
		)
		(pad "AC23" smd circle
			(at 5.999988 5.999988 180)
			(size 0.3556 0.3556)
			(layers "F.Cu" "F.Mask" "F.Paste")
			(net "GND")
		)
		(pad "AC24" smd circle
			(at 6.800088 5.999988 180)
			(size 0.3556 0.3556)
			(layers "F.Cu" "F.Mask" "F.Paste")
			(net "GND")
		)
		(pad "AC25" smd circle
			(at 7.599934 5.999988 180)
			(size 0.3556 0.3556)
			(layers "F.Cu" "F.Mask" "F.Paste")
			(net "GND")
		)
		(pad "AC26" smd circle
			(at 8.400034 5.999988 180)
			(size 0.3556 0.3556)
			(layers "F.Cu" "F.Mask" "F.Paste")
			(net "GND")
		)
		(pad "AC27" smd circle
			(at 9.19988 5.999988 180)
			(size 0.3556 0.3556)
			(layers "F.Cu" "F.Mask" "F.Paste")
			(net "P1V8")
		)
		(pad "AC28" smd circle
			(at 9.99998 5.999988 180)
			(size 0.3556 0.3556)
			(layers "F.Cu" "F.Mask" "F.Paste")
			(net "IOC_GPIO_28")
		)
		(pad "AC29" smd circle
			(at 10.80008 5.999988 180)
			(size 0.3556 0.3556)
			(layers "F.Cu" "F.Mask" "F.Paste")
			(net "IOC_GPIO_30")
		)
		(pad "AC30" smd circle
			(at 11.599926 5.999988 180)
			(size 0.3556 0.3556)
			(layers "F.Cu" "F.Mask" "F.Paste")
			(net "IOC_GPIO_8")
		)
		(pad "AD1" smd circle
			(at -11.599926 6.800088 180)
			(size 0.3556 0.3556)
			(layers "F.Cu" "F.Mask" "F.Paste")
			(net "PHY_IOC_TO_CON_A_3_DP_C")
		)
	)
)
